(kicad_pcb
	(version 20260206)
	(generator "pcbnew")
	(generator_version "10.0")
	(general
		(thickness 1.6)
		(legacy_teardrops no)
	)
	(paper "A4")
	(title_block
		(title "Bryce Canyon_F.DPB_16315-1-OCP.brd")
		(comment 1 "Bryce Canyon / footprints 1958-1964 of 2223")
	)
	(layers
		(0 "F.Cu" signal "TOP")
		(4 "In1.Cu" signal "L2GND")
		(6 "In2.Cu" signal "L3")
		(8 "In3.Cu" signal "L4GND")
		(10 "In4.Cu" signal "L5")
		(12 "In5.Cu" signal "L6VCC")
		(14 "In6.Cu" signal "L7VCC")
		(16 "In7.Cu" signal "L8")
		(18 "In8.Cu" signal "L9GND")
		(20 "In9.Cu" signal "L10")
		(22 "In10.Cu" signal "L11GND")
		(2 "B.Cu" signal "BOTTOM")
		(9 "F.Adhes" user "F.Adhesive")
		(11 "B.Adhes" user "B.Adhesive")
		(13 "F.Paste" user "Package Geometry/Pastemask Top")
		(15 "B.Paste" user "Package Geometry/Pastemask Bottom")
		(5 "F.SilkS" user "Ref Des/Silkscreen Top")
		(7 "B.SilkS" user "Ref Des/Silkscreen Bottom")
		(1 "F.Mask" user "Board Geometry/Soldermask Top")
		(3 "B.Mask" user "Board Geometry/Soldermask Bottom")
		(17 "Dwgs.User" user "User.Drawings")
		(19 "Cmts.User" user "User.Comments")
		(21 "Eco1.User" user "User.Eco1")
		(23 "Eco2.User" user "User.Eco2")
		(25 "Edge.Cuts" user "Board Geometry/Outline")
		(27 "Margin" user)
		(31 "F.CrtYd" user "Package Geometry/Place Bound Top")
		(29 "B.CrtYd" user "Package Geometry/Place Bound Bottom")
		(35 "F.Fab" user "Ref Des/Assembly Top")
		(33 "B.Fab" user "Ref Des/Assembly Bottom")
	)
	(footprint ""
		(layer "F.Cu")
		(at 286.015938 -224.384616)
		(property "Reference" "TC16"
			(at 0 0 0)
			(layer "F.SilkS")
			(hide yes)
			(effects
				(font
					(size 1.27 1.27)
				)
			)
		)
		(property "Value" "SE270U16VM-8-GP"
			(at -4.5974 -2.54 0)
			(unlocked yes)
			(layer "F.Fab")
			(hide yes)
			(effects
				(font
					(size 1.016 1.016)
					(thickness 0.1524)
				)
			)
		)
		(property "Device Type" "SE361416H394"
			(at -4.5974 -4.064 0)
			(unlocked yes)
			(layer "F.Fab")
			(hide yes)
			(effects
				(font
					(size 1.016 1.016)
					(thickness 0.1524)
				)
			)
		)
		(duplicate_pad_numbers_are_jumpers no)
		(fp_line
			(start -3.556 -3.4163)
			(end -2.3622 -4.6101)
			(stroke
				(width 0.1524)
				(type default)
			)
			(layer "F.SilkS")
		)
		(fp_line
			(start -3.556 4.6101)
			(end -3.556 -3.4163)
			(stroke
				(width 0.1524)
				(type default)
			)
			(layer "F.SilkS")
		)
		(fp_line
			(start -2.3622 -4.6101)
			(end 2.3622 -4.6101)
			(stroke
				(width 0.1524)
				(type default)
			)
			(layer "F.SilkS")
		)
		(fp_line
			(start 2.3622 -4.6101)
			(end 3.556 -3.4163)
			(stroke
				(width 0.1524)
				(type default)
			)
			(layer "F.SilkS")
		)
		(fp_line
			(start 3.556 -3.4163)
			(end 3.556 4.6101)
			(stroke
				(width 0.1524)
				(type default)
			)
			(layer "F.SilkS")
		)
		(fp_line
			(start 3.556 4.6101)
			(end -3.556 4.6101)
			(stroke
				(width 0.1524)
				(type default)
			)
			(layer "F.SilkS")
		)
		(fp_rect
			(start -3.302 3.6449)
			(end 3.302 -3.6449)
			(stroke
				(width 0)
				(type default)
			)
			(fill no)
			(layer "F.CrtYd")
		)
		(fp_poly
			(pts
				(xy 3.81 4.6863) (xy 3.81 -3.4925) (xy 3.302 -3.4925) (xy 3.302 3.6449) (xy -3.302 3.6449) (xy -3.302 -3.6449)
				(xy 3.302 -3.6449) (xy 3.302 -3.5052) (xy 3.81 -3.5052) (xy 3.81 -4.6863) (xy -3.81 -4.6863) (xy -3.81 4.6863)
			)
			(stroke
				(width 0)
				(type default)
			)
			(fill no)
			(layer "F.CrtYd")
		)
		(fp_rect
			(start -3.81 4.6863)
			(end 3.81 -4.6863)
			(stroke
				(width 0)
				(type default)
			)
			(fill no)
			(layer "F.Fab")
		)
		(pad "1" smd rect
			(at 0 -2.574036)
			(size 1.4224 3.556)
			(layers "F.Cu" "F.Mask" "F.Paste")
			(net "P12V_A")
		)
		(pad "2" smd rect
			(at 0 2.574036)
			(size 1.4224 3.556)
			(layers "F.Cu" "F.Mask" "F.Paste")
			(net "GND")
		)
	)
	(footprint ""
		(layer "F.Cu")
		(at 145.17116 -145.38071 180)
		(property "Reference" "R1061"
			(at 0 0 180)
			(layer "F.SilkS")
			(hide yes)
			(effects
				(font
					(size 1.27 1.27)
				)
			)
		)
		(property "Value" "22D6R2F-L1-GP"
			(at 0.064008 -3.993896 180)
			(unlocked yes)
			(layer "F.Fab")
			(hide yes)
			(effects
				(font
					(size 1.016 1.016)
					(thickness 0.1524)
				)
			)
		)
		(property "Device Type" "R402H16"
			(at 0.064008 -5.517896 180)
			(unlocked yes)
			(layer "F.Fab")
			(hide yes)
			(effects
				(font
					(size 1.016 1.016)
					(thickness 0.1524)
				)
			)
		)
		(duplicate_pad_numbers_are_jumpers no)
		(fp_line
			(start 0.508 -0.9398)
			(end -0.508 -0.9398)
			(stroke
				(width 0.1524)
				(type default)
			)
			(layer "F.SilkS")
		)
		(fp_line
			(start -0.508 -0.9398)
			(end -0.508 0.9398)
			(stroke
				(width 0.1524)
				(type default)
			)
			(layer "F.SilkS")
		)
		(fp_rect
			(start -0.508 0.9398)
			(end 0.508 -0.9398)
			(stroke
				(width 0)
				(type default)
			)
			(fill no)
			(layer "F.CrtYd")
		)
		(fp_rect
			(start -0.508 0.9398)
			(end 0.508 -0.9398)
			(stroke
				(width 0)
				(type default)
			)
			(fill no)
			(layer "F.Fab")
		)
		(pad "1" smd custom
			(at 0 -0.4445 180)
			(size 0.1397 0.1397)
			(layers "F.Cu" "F.Mask" "F.Paste")
			(net "MB0_ISTART_R")
			(options
				(clearance outline)
				(anchor circle)
			)
			(primitives
				(gr_poly
					(pts
						(arc
							(start -0.1778 -0.2794)
							(mid -0.249642 -0.249642)
							(end -0.2794 -0.1778)
						)
						(arc
							(start -0.2794 0.1778)
							(mid -0.249642 0.249642)
							(end -0.1778 0.2794)
						)
						(arc
							(start 0.1778 0.2794)
							(mid 0.249642 0.249642)
							(end 0.2794 0.1778)
						)
						(arc
							(start 0.2794 -0.1778)
							(mid 0.249642 -0.249642)
							(end 0.1778 -0.2794)
						)
					)
					(width 0)
					(fill yes)
				)
			)
		)
		(pad "2" smd custom
			(at 0 0.4445 180)
			(size 0.1397 0.1397)
			(layers "F.Cu" "F.Mask" "F.Paste")
			(net "AGND_CURRENT_MONOA")
			(options
				(clearance outline)
				(anchor circle)
			)
			(primitives
				(gr_poly
					(pts
						(arc
							(start -0.1778 -0.2794)
							(mid -0.249642 -0.249642)
							(end -0.2794 -0.1778)
						)
						(arc
							(start -0.2794 0.1778)
							(mid -0.249642 0.249642)
							(end -0.1778 0.2794)
						)
						(arc
							(start 0.1778 0.2794)
							(mid 0.249642 0.249642)
							(end 0.2794 0.1778)
						)
						(arc
							(start 0.2794 -0.1778)
							(mid 0.249642 -0.249642)
							(end 0.1778 -0.2794)
						)
					)
					(width 0)
					(fill yes)
				)
			)
		)
	)
	(footprint ""
		(layer "F.Cu")
		(at 127.113284 -43.660568 90)
		(property "Reference" "C390"
			(at 0 0 90)
			(layer "F.SilkS")
			(hide yes)
			(effects
				(font
					(size 1.27 1.27)
				)
			)
		)
		(property "Value" "SCD01U16V1KX-GP"
			(at -2.8321 -1.7399 90)
			(unlocked yes)
			(layer "F.Fab")
			(hide yes)
			(effects
				(font
					(size 1.016 1.016)
					(thickness 0.1524)
				)
			)
		)
		(property "Device Type" "C0201H13"
			(at -2.8321 -3.2639 90)
			(unlocked yes)
			(layer "F.Fab")
			(hide yes)
			(effects
				(font
					(size 1.016 1.016)
					(thickness 0.1524)
				)
			)
		)
		(duplicate_pad_numbers_are_jumpers no)
		(fp_rect
			(start -0.2794 0.6477)
			(end 0.2794 -0.6477)
			(stroke
				(width 0)
				(type default)
			)
			(fill no)
			(layer "F.CrtYd")
		)
		(fp_rect
			(start -0.2794 0.6477)
			(end 0.2794 -0.6477)
			(stroke
				(width 0)
				(type default)
			)
			(fill no)
			(layer "F.Fab")
		)
		(pad "1" smd custom
			(at 0 -0.2794 90)
			(size 0.0762 0.0762)
			(layers "F.Cu" "F.Mask" "F.Paste")
			(net "SAS_HDD_RX_P27")
			(options
				(clearance outline)
				(anchor circle)
			)
			(primitives
				(gr_poly
					(pts
						(arc
							(start 0.1524 -0.127)
							(mid 0.137521 -0.162921)
							(end 0.1016 -0.1778)
						)
						(arc
							(start -0.1016 -0.1778)
							(mid -0.137521 -0.162921)
							(end -0.1524 -0.127)
						)
						(arc
							(start -0.1524 0.127)
							(mid -0.137521 0.162921)
							(end -0.1016 0.1778)
						)
						(arc
							(start 0.1016 0.1778)
							(mid 0.137521 0.162921)
							(end 0.1524 0.127)
						)
					)
					(width 0)
					(fill yes)
				)
			)
		)
		(pad "2" smd custom
			(at 0 0.2794 90)
			(size 0.0762 0.0762)
			(layers "F.Cu" "F.Mask" "F.Paste")
			(net "PHY_SCC_A_TO_DRV_A_27_DP")
			(options
				(clearance outline)
				(anchor circle)
			)
			(primitives
				(gr_poly
					(pts
						(arc
							(start 0.1524 -0.127)
							(mid 0.137521 -0.162921)
							(end 0.1016 -0.1778)
						)
						(arc
							(start -0.1016 -0.1778)
							(mid -0.137521 -0.162921)
							(end -0.1524 -0.127)
						)
						(arc
							(start -0.1524 0.127)
							(mid -0.137521 0.162921)
							(end -0.1016 0.1778)
						)
						(arc
							(start 0.1016 0.1778)
							(mid 0.137521 0.162921)
							(end 0.1524 0.127)
						)
					)
					(width 0)
					(fill yes)
				)
			)
		)
	)
	(footprint ""
		(layer "F.Cu")
		(at 395.20495 -42.585894)
		(property "Reference" "R878"
			(at 0 0 0)
			(layer "F.SilkS")
			(hide yes)
			(effects
				(font
					(size 1.27 1.27)
				)
			)
		)
		(property "Value" "4K7R2J-2-GP"
			(at 0.064008 -3.993896 0)
			(unlocked yes)
			(layer "F.Fab")
			(hide yes)
			(effects
				(font
					(size 1.016 1.016)
					(thickness 0.1524)
				)
			)
		)
		(property "Device Type" "R402H16"
			(at 0.064008 -5.517896 0)
			(unlocked yes)
			(layer "F.Fab")
			(hide yes)
			(effects
				(font
					(size 1.016 1.016)
					(thickness 0.1524)
				)
			)
		)
		(duplicate_pad_numbers_are_jumpers no)
		(fp_line
			(start -0.508 -0.9398)
			(end -0.508 0.9398)
			(stroke
				(width 0.1524)
				(type default)
			)
			(layer "F.SilkS")
		)
		(fp_line
			(start 0.508 -0.9398)
			(end -0.508 -0.9398)
			(stroke
				(width 0.1524)
				(type default)
			)
			(layer "F.SilkS")
		)
		(fp_rect
			(start -0.508 0.9398)
			(end 0.508 -0.9398)
			(stroke
				(width 0)
				(type default)
			)
			(fill no)
			(layer "F.CrtYd")
		)
		(fp_rect
			(start -0.508 0.9398)
			(end 0.508 -0.9398)
			(stroke
				(width 0)
				(type default)
			)
			(fill no)
			(layer "F.Fab")
		)
		(pad "1" smd custom
			(at 0 -0.4445)
			(size 0.1397 0.1397)
			(layers "F.Cu" "F.Mask" "F.Paste")
			(net "SW_PWR_R_HDD32")
			(options
				(clearance outline)
				(anchor circle)
			)
			(primitives
				(gr_poly
					(pts
						(arc
							(start -0.1778 -0.2794)
							(mid -0.249642 -0.249642)
							(end -0.2794 -0.1778)
						)
						(arc
							(start -0.2794 0.1778)
							(mid -0.249642 0.249642)
							(end -0.1778 0.2794)
						)
						(arc
							(start 0.1778 0.2794)
							(mid 0.249642 0.249642)
							(end 0.2794 0.1778)
						)
						(arc
							(start 0.2794 -0.1778)
							(mid 0.249642 -0.249642)
							(end 0.1778 -0.2794)
						)
					)
					(width 0)
					(fill yes)
				)
			)
		)
		(pad "2" smd custom
			(at 0 0.4445)
			(size 0.1397 0.1397)
			(layers "F.Cu" "F.Mask" "F.Paste")
			(net "GND")
			(options
				(clearance outline)
				(anchor circle)
			)
			(primitives
				(gr_poly
					(pts
						(arc
							(start -0.1778 -0.2794)
							(mid -0.249642 -0.249642)
							(end -0.2794 -0.1778)
						)
						(arc
							(start -0.2794 0.1778)
							(mid -0.249642 0.249642)
							(end -0.1778 0.2794)
						)
						(arc
							(start 0.1778 0.2794)
							(mid 0.249642 0.249642)
							(end 0.2794 0.1778)
						)
						(arc
							(start 0.2794 -0.1778)
							(mid 0.249642 -0.249642)
							(end 0.1778 -0.2794)
						)
					)
					(width 0)
					(fill yes)
				)
			)
		)
	)
	(footprint ""
		(layer "F.Cu")
		(at 148.548344 -128.697228 -90)
		(property "Reference" "R143"
			(at 0 0 270)
			(layer "F.SilkS")
			(hide yes)
			(effects
				(font
					(size 1.27 1.27)
				)
			)
		)
		(property "Value" "0R5J-5-GP"
			(at 0 -8.9535 270)
			(unlocked yes)
			(layer "F.Fab")
			(hide yes)
			(effects
				(font
					(size 1.27 1.016)
					(thickness 0.1524)
				)
			)
		)
		(property "Device Type" "R805H24"
			(at 0 -10.6299 270)
			(unlocked yes)
			(layer "F.Fab")
			(hide yes)
			(effects
				(font
					(size 1.27 1.016)
					(thickness 0.1524)
				)
			)
		)
		(duplicate_pad_numbers_are_jumpers no)
		(fp_line
			(start -0.889 1.7018)
			(end 0.889 1.7018)
			(stroke
				(width 0.1524)
				(type default)
			)
			(layer "F.SilkS")
		)
		(fp_line
			(start 0.889 1.7018)
			(end 0.889 -0.508)
			(stroke
				(width 0.1524)
				(type default)
			)
			(layer "F.SilkS")
		)
		(fp_line
			(start -0.889 0.0762)
			(end -0.889 1.7018)
			(stroke
				(width 0.1524)
				(type default)
			)
			(layer "F.SilkS")
		)
		(fp_line
			(start -0.889 -1.7018)
			(end -0.889 0.2794)
			(stroke
				(width 0.1524)
				(type default)
			)
			(layer "F.SilkS")
		)
		(fp_line
			(start 0.889 -1.7018)
			(end 0.889 -0.381)
			(stroke
				(width 0.1524)
				(type default)
			)
			(layer "F.SilkS")
		)
		(fp_line
			(start 0.889 -1.7018)
			(end -0.889 -1.7018)
			(stroke
				(width 0.1524)
				(type default)
			)
			(layer "F.SilkS")
		)
		(fp_poly
			(pts
				(xy 0.9652 -1.778) (xy 0.9652 1.778) (xy -0.9652 1.778) (xy -0.9652 -1.778)
			)
			(stroke
				(width 0)
				(type default)
			)
			(fill no)
			(layer "F.CrtYd")
		)
		(fp_rect
			(start -0.9652 1.778)
			(end 0.9652 -1.778)
			(stroke
				(width 0)
				(type default)
			)
			(fill no)
			(layer "F.Fab")
		)
		(pad "1" smd rect
			(at 0 -0.9652 270)
			(size 1.397 1.143)
			(layers "F.Cu" "F.Mask" "F.Paste")
			(net "MB0_CM_GATE_R")
		)
		(pad "2" smd rect
			(at 0 0.9652 270)
			(size 1.397 1.143)
			(layers "F.Cu" "F.Mask" "F.Paste")
			(net "MB0_CM_GATE_C")
		)
	)
	(footprint ""
		(layer "F.Cu")
		(at 350.320102 -61.127894 -90)
		(property "Reference" "C449"
			(at 0 0 270)
			(layer "F.SilkS")
			(hide yes)
			(effects
				(font
					(size 1.27 1.27)
				)
			)
		)
		(property "Value" "SCD01U50V2KX-1GP"
			(at 1.1811 -2.7051 270)
			(unlocked yes)
			(layer "F.Fab")
			(hide yes)
			(effects
				(font
					(size 1.016 1.016)
					(thickness 0.1524)
				)
			)
		)
		(property "Device Type" "C402H22"
			(at 1.1811 -4.2291 270)
			(unlocked yes)
			(layer "F.Fab")
			(hide yes)
			(effects
				(font
					(size 1.016 1.016)
					(thickness 0.1524)
				)
			)
		)
		(duplicate_pad_numbers_are_jumpers no)
		(fp_rect
			(start -0.4318 0.9525)
			(end 0.4318 -0.9525)
			(stroke
				(width 0)
				(type default)
			)
			(fill no)
			(layer "F.CrtYd")
		)
		(fp_rect
			(start -0.4318 0.9525)
			(end 0.4318 -0.9525)
			(stroke
				(width 0)
				(type default)
			)
			(fill no)
			(layer "F.Fab")
		)
		(pad "1" smd custom
			(at 0 -0.4445 270)
			(size 0.1524 0.1524)
			(layers "F.Cu" "F.Mask" "F.Paste")
			(net "HDD_PRSNT_31")
			(options
				(clearance outline)
				(anchor circle)
			)
			(primitives
				(gr_poly
					(pts
						(arc
							(start 0.3048 -0.2032)
							(mid 0.275042 -0.275042)
							(end 0.2032 -0.3048)
						)
						(arc
							(start -0.2032 -0.3048)
							(mid -0.275042 -0.275042)
							(end -0.3048 -0.2032)
						)
						(arc
							(start -0.3048 0.2032)
							(mid -0.275042 0.275042)
							(end -0.2032 0.3048)
						)
						(arc
							(start 0.2032 0.3048)
							(mid 0.275042 0.275042)
							(end 0.3048 0.2032)
						)
					)
					(width 0)
					(fill yes)
				)
			)
		)
		(pad "2" smd custom
			(at 0 0.4445 270)
			(size 0.1524 0.1524)
			(layers "F.Cu" "F.Mask" "F.Paste")
			(net "GND")
			(options
				(clearance outline)
				(anchor circle)
			)
			(primitives
				(gr_poly
					(pts
						(arc
							(start 0.3048 -0.2032)
							(mid 0.275042 -0.275042)
							(end 0.2032 -0.3048)
						)
						(arc
							(start -0.2032 -0.3048)
							(mid -0.275042 -0.275042)
							(end -0.3048 -0.2032)
						)
						(arc
							(start -0.3048 0.2032)
							(mid -0.275042 0.275042)
							(end -0.2032 0.3048)
						)
						(arc
							(start 0.2032 0.3048)
							(mid 0.275042 0.275042)
							(end 0.3048 0.2032)
						)
					)
					(width 0)
					(fill yes)
				)
			)
		)
	)
	(footprint ""
		(layer "F.Cu")
		(at 403.107144 -242.820698 180)
		(property "Reference" "Q272"
			(at 0 0 180)
			(layer "F.SilkS")
			(hide yes)
			(effects
				(font
					(size 1.27 1.27)
				)
			)
		)
		(property "Value" "SSM3K324R-GP"
			(at 0.127 -8.9662 180)
			(unlocked yes)
			(layer "F.Fab")
			(hide yes)
			(effects
				(font
					(size 1.016 1.016)
					(thickness 0.1524)
				)
			)
		)
		(property "Device Type" "SOT23DGS2D4H35"
			(at 0.127 -10.4902 180)
			(unlocked yes)
			(layer "F.Fab")
			(hide yes)
			(effects
				(font
					(size 1.016 1.016)
					(thickness 0.1524)
				)
			)
		)
		(duplicate_pad_numbers_are_jumpers no)
		(fp_line
			(start 1.651 1.778)
			(end 1.651 -1.778)
			(stroke
				(width 0.1524)
				(type default)
			)
			(layer "F.SilkS")
		)
		(fp_line
			(start 1.651 -1.778)
			(end -1.651 -1.778)
			(stroke
				(width 0.1524)
				(type default)
			)
			(layer "F.SilkS")
		)
		(fp_line
			(start -1.651 1.778)
			(end 1.651 1.778)
			(stroke
				(width 0.1524)
				(type default)
			)
			(layer "F.SilkS")
		)
		(fp_line
			(start -1.651 -1.778)
			(end -1.651 1.778)
			(stroke
				(width 0.1524)
				(type default)
			)
			(layer "F.SilkS")
		)
		(fp_poly
			(pts
				(xy -1.778 1.8796) (xy -1.778 -1.8796) (xy 1.778 -1.8796) (xy 1.778 1.8796)
			)
			(stroke
				(width 0)
				(type default)
			)
			(fill no)
			(layer "F.CrtYd")
		)
		(fp_poly
			(pts
				(xy -1.778 1.8796) (xy -1.778 -1.8796) (xy 1.778 -1.8796) (xy 1.778 1.8796)
			)
			(stroke
				(width 0)
				(type default)
			)
			(fill no)
			(layer "F.Fab")
		)
		(pad "D" smd custom
			(at 0 -0.9525 180)
			(size 0.1905 0.1905)
			(layers "F.Cu" "F.Mask" "F.Paste")
			(net "DRV_ACT_9_N")
			(options
				(clearance outline)
				(anchor circle)
			)
			(primitives
				(gr_poly
					(pts
						(arc
							(start -0.1778 0.5715)
							(mid -0.321484 0.511984)
							(end -0.381 0.3683)
						)
						(arc
							(start -0.381 -0.3683)
							(mid -0.321484 -0.511984)
							(end -0.1778 -0.5715)
						)
						(arc
							(start 0.1778 -0.5715)
							(mid 0.321484 -0.511984)
							(end 0.381 -0.3683)
						)
						(arc
							(start 0.381 0.3683)
							(mid 0.321484 0.511984)
							(end 0.1778 0.5715)
						)
					)
					(width 0)
					(fill yes)
				)
			)
		)
		(pad "G" smd custom
			(at -0.98425 0.9525 180)
			(size 0.1905 0.1905)
			(layers "F.Cu" "F.Mask" "F.Paste")
			(net "DRIVE_A_9_ACT")
			(options
				(clearance outline)
				(anchor circle)
			)
			(primitives
				(gr_poly
					(pts
						(arc
							(start -0.1778 0.5715)
							(mid -0.321484 0.511984)
							(end -0.381 0.3683)
						)
						(arc
							(start -0.381 -0.3683)
							(mid -0.321484 -0.511984)
							(end -0.1778 -0.5715)
						)
						(arc
							(start 0.1778 -0.5715)
							(mid 0.321484 -0.511984)
							(end 0.381 -0.3683)
						)
						(arc
							(start 0.381 0.3683)
							(mid 0.321484 0.511984)
							(end 0.1778 0.5715)
						)
					)
					(width 0)
					(fill yes)
				)
			)
		)
		(pad "S" smd custom
			(at 0.98425 0.9525 180)
			(size 0.1905 0.1905)
			(layers "F.Cu" "F.Mask" "F.Paste")
			(net "GND")
			(options
				(clearance outline)
				(anchor circle)
			)
			(primitives
				(gr_poly
					(pts
						(arc
							(start -0.1778 0.5715)
							(mid -0.321484 0.511984)
							(end -0.381 0.3683)
						)
						(arc
							(start -0.381 -0.3683)
							(mid -0.321484 -0.511984)
							(end -0.1778 -0.5715)
						)
						(arc
							(start 0.1778 -0.5715)
							(mid 0.321484 -0.511984)
							(end 0.381 -0.3683)
						)
						(arc
							(start 0.381 0.3683)
							(mid 0.321484 0.511984)
							(end 0.1778 0.5715)
						)
					)
					(width 0)
					(fill yes)
				)
			)
		)
	)
)
